(kicad_pcb
	(version 20260206)
	(generator "pcbnew")
	(generator_version "10.0")
	(general
		(thickness 1.6)
		(legacy_teardrops no)
	)
	(paper "A4")
	(title_block
		(title "01162023_DA0F0TEBIF0_F0T_Expander_BD_F_brd_V02_OCP.brd")
		(comment 1 "Grand Teton / footprints 692-699 of 9728")
	)
	(layers
		(0 "F.Cu" signal "TOP")
		(4 "In1.Cu" signal "GND")
		(6 "In2.Cu" signal "VCC")
		(8 "In3.Cu" signal "VCC1")
		(10 "In4.Cu" signal "GND1")
		(12 "In5.Cu" signal "IN1")
		(14 "In6.Cu" signal "GND2")
		(16 "In7.Cu" signal "IN2")
		(18 "In8.Cu" signal "GND3")
		(20 "In9.Cu" signal "IN3")
		(22 "In10.Cu" signal "GND4")
		(24 "In11.Cu" signal "IN4")
		(26 "In12.Cu" signal "GND5")
		(28 "In13.Cu" signal "IN5")
		(30 "In14.Cu" signal "GND6")
		(32 "In15.Cu" signal "IN6")
		(34 "In16.Cu" signal "GND7")
		(2 "B.Cu" signal "BOTTOM")
		(9 "F.Adhes" user "F.Adhesive")
		(11 "B.Adhes" user "B.Adhesive")
		(13 "F.Paste" user "Package Geometry/Pastemask Top")
		(15 "B.Paste" user "Package Geometry/Pastemask Bottom")
		(5 "F.SilkS" user "Ref Des/Silkscreen Top")
		(7 "B.SilkS" user "Ref Des/Silkscreen Bottom")
		(1 "F.Mask" user "Board Geometry/Soldermask Top")
		(3 "B.Mask" user "Board Geometry/Soldermask Bottom")
		(17 "Dwgs.User" user "User.Drawings")
		(19 "Cmts.User" user "User.Comments")
		(21 "Eco1.User" user "User.Eco1")
		(23 "Eco2.User" user "User.Eco2")
		(25 "Edge.Cuts" user "Board Geometry/Outline")
		(27 "Margin" user)
		(31 "F.CrtYd" user "Package Geometry/Place Bound Top")
		(29 "B.CrtYd" user "Package Geometry/Place Bound Bottom")
		(35 "F.Fab" user "Ref Des/Assembly Top")
		(33 "B.Fab" user "Ref Des/Assembly Bottom")
	)
	(footprint ""
		(layer "F.Cu")
		(at 314.861448 -124.076714 180)
		(property "Reference" "C448"
			(at 0 0 180)
			(layer "F.SilkS")
			(hide yes)
			(effects
				(font
					(size 1.27 1.27)
				)
			)
		)
		(property "Value" ""
			(at 0 0 180)
			(layer "F.Fab")
			(effects
				(font
					(size 1.27 1.27)
				)
			)
		)
		(duplicate_pad_numbers_are_jumpers no)
		(fp_line
			(start 0.299974 0.150114)
			(end -0.299974 0.150114)
			(stroke
				(width 0.1)
				(type default)
			)
			(layer "F.Fab")
		)
		(fp_line
			(start 0.299974 -0.150114)
			(end 0.299974 0.150114)
			(stroke
				(width 0.1)
				(type default)
			)
			(layer "F.Fab")
		)
		(fp_line
			(start -0.299974 0.150114)
			(end -0.299974 -0.150114)
			(stroke
				(width 0.1)
				(type default)
			)
			(layer "F.Fab")
		)
		(fp_line
			(start -0.299974 -0.150114)
			(end 0.299974 -0.150114)
			(stroke
				(width 0.1)
				(type default)
			)
			(layer "F.Fab")
		)
		(pad "1" smd rect
			(at -0.2667 0 180)
			(size 0.3048 0.381)
			(layers "F.Cu" "F.Mask" "F.Paste")
			(net "P5E_PEX2_STN0_TX_DN<3>")
		)
		(pad "2" smd rect
			(at 0.2667 0 180)
			(size 0.3048 0.381)
			(layers "F.Cu" "F.Mask" "F.Paste")
			(net "P5E_PEX2_STN0_TX_C_DN<3>")
		)
	)
	(footprint ""
		(layer "F.Cu")
		(at 263.495282 -345.766898)
		(property "Reference" "R6656"
			(at 0 0 0)
			(layer "F.SilkS")
			(hide yes)
			(effects
				(font
					(size 1.27 1.27)
				)
			)
		)
		(property "Value" ""
			(at 0 0 0)
			(layer "F.Fab")
			(effects
				(font
					(size 1.27 1.27)
				)
			)
		)
		(duplicate_pad_numbers_are_jumpers no)
		(fp_line
			(start -0.7874 -0.4064)
			(end 0.7874 -0.4064)
			(stroke
				(width 0.1524)
				(type default)
			)
			(layer "F.SilkS")
		)
		(fp_line
			(start -0.7874 0.4064)
			(end -0.7874 -0.4064)
			(stroke
				(width 0.1524)
				(type default)
			)
			(layer "F.SilkS")
		)
		(fp_line
			(start 0.7874 -0.4064)
			(end 0.7874 0.4064)
			(stroke
				(width 0.1524)
				(type default)
			)
			(layer "F.SilkS")
		)
		(fp_line
			(start 0.7874 0.4064)
			(end -0.7874 0.4064)
			(stroke
				(width 0.1524)
				(type default)
			)
			(layer "F.SilkS")
		)
		(fp_line
			(start -0.67945 -0.305054)
			(end -0.12065 -0.305054)
			(stroke
				(width 0.1)
				(type default)
			)
			(layer "F.Fab")
		)
		(fp_line
			(start -0.67945 0.3048)
			(end -0.67945 -0.305054)
			(stroke
				(width 0.1)
				(type default)
			)
			(layer "F.Fab")
		)
		(fp_line
			(start -0.12065 -0.305054)
			(end -0.12065 -0.2794)
			(stroke
				(width 0.1)
				(type default)
			)
			(layer "F.Fab")
		)
		(fp_line
			(start -0.12065 -0.2794)
			(end 0.12065 -0.2794)
			(stroke
				(width 0.1)
				(type default)
			)
			(layer "F.Fab")
		)
		(fp_line
			(start -0.12065 0.2794)
			(end -0.12065 0.3048)
			(stroke
				(width 0.1)
				(type default)
			)
			(layer "F.Fab")
		)
		(fp_line
			(start -0.12065 0.3048)
			(end -0.67945 0.3048)
			(stroke
				(width 0.1)
				(type default)
			)
			(layer "F.Fab")
		)
		(fp_line
			(start 0.120396 0.2794)
			(end -0.12065 0.2794)
			(stroke
				(width 0.1)
				(type default)
			)
			(layer "F.Fab")
		)
		(fp_line
			(start 0.120396 0.3048)
			(end 0.120396 0.2794)
			(stroke
				(width 0.1)
				(type default)
			)
			(layer "F.Fab")
		)
		(fp_line
			(start 0.12065 -0.3048)
			(end 0.67945 -0.3048)
			(stroke
				(width 0.1)
				(type default)
			)
			(layer "F.Fab")
		)
		(fp_line
			(start 0.12065 -0.2794)
			(end 0.12065 -0.3048)
			(stroke
				(width 0.1)
				(type default)
			)
			(layer "F.Fab")
		)
		(fp_line
			(start 0.67945 -0.3048)
			(end 0.67945 0.3048)
			(stroke
				(width 0.1)
				(type default)
			)
			(layer "F.Fab")
		)
		(fp_line
			(start 0.67945 0.3048)
			(end 0.120396 0.3048)
			(stroke
				(width 0.1)
				(type default)
			)
			(layer "F.Fab")
		)
		(pad "1" smd circle
			(at -0.40005 0)
			(size 0 0)
			(layers "F.Cu" "F.Mask" "F.Paste")
			(net "HSC_CSOUT")
		)
		(pad "2" smd circle
			(at 0.40005 0)
			(size 0 0)
			(layers "F.Cu" "F.Mask" "F.Paste")
			(net "HSC_D_OC_R")
		)
	)
	(footprint ""
		(layer "F.Cu")
		(at 447.247264 -19.33956)
		(property "Reference" "C3982"
			(at 0 0 0)
			(layer "F.SilkS")
			(hide yes)
			(effects
				(font
					(size 1.27 1.27)
				)
			)
		)
		(property "Value" ""
			(at 0 0 0)
			(layer "F.Fab")
			(effects
				(font
					(size 1.27 1.27)
				)
			)
		)
		(duplicate_pad_numbers_are_jumpers no)
		(fp_line
			(start -0.7874 -0.4064)
			(end 0.7874 -0.4064)
			(stroke
				(width 0.1524)
				(type default)
			)
			(layer "F.SilkS")
		)
		(fp_line
			(start -0.7874 0.4064)
			(end -0.7874 -0.4064)
			(stroke
				(width 0.1524)
				(type default)
			)
			(layer "F.SilkS")
		)
		(fp_line
			(start 0.7874 -0.4064)
			(end 0.7874 0.4064)
			(stroke
				(width 0.1524)
				(type default)
			)
			(layer "F.SilkS")
		)
		(fp_line
			(start 0.7874 0.4064)
			(end -0.7874 0.4064)
			(stroke
				(width 0.1524)
				(type default)
			)
			(layer "F.SilkS")
		)
		(fp_line
			(start -0.67945 -0.305054)
			(end -0.12065 -0.305054)
			(stroke
				(width 0.1)
				(type default)
			)
			(layer "F.Fab")
		)
		(fp_line
			(start -0.67945 0.3048)
			(end -0.67945 -0.305054)
			(stroke
				(width 0.1)
				(type default)
			)
			(layer "F.Fab")
		)
		(fp_line
			(start -0.12065 -0.305054)
			(end -0.12065 -0.2794)
			(stroke
				(width 0.1)
				(type default)
			)
			(layer "F.Fab")
		)
		(fp_line
			(start -0.12065 -0.2794)
			(end 0.12065 -0.2794)
			(stroke
				(width 0.1)
				(type default)
			)
			(layer "F.Fab")
		)
		(fp_line
			(start -0.12065 0.2794)
			(end -0.12065 0.3048)
			(stroke
				(width 0.1)
				(type default)
			)
			(layer "F.Fab")
		)
		(fp_line
			(start -0.12065 0.3048)
			(end -0.67945 0.3048)
			(stroke
				(width 0.1)
				(type default)
			)
			(layer "F.Fab")
		)
		(fp_line
			(start 0.120396 0.2794)
			(end -0.12065 0.2794)
			(stroke
				(width 0.1)
				(type default)
			)
			(layer "F.Fab")
		)
		(fp_line
			(start 0.120396 0.3048)
			(end 0.120396 0.2794)
			(stroke
				(width 0.1)
				(type default)
			)
			(layer "F.Fab")
		)
		(fp_line
			(start 0.12065 -0.3048)
			(end 0.67945 -0.3048)
			(stroke
				(width 0.1)
				(type default)
			)
			(layer "F.Fab")
		)
		(fp_line
			(start 0.12065 -0.2794)
			(end 0.12065 -0.3048)
			(stroke
				(width 0.1)
				(type default)
			)
			(layer "F.Fab")
		)
		(fp_line
			(start 0.67945 -0.3048)
			(end 0.67945 0.3048)
			(stroke
				(width 0.1)
				(type default)
			)
			(layer "F.Fab")
		)
		(fp_line
			(start 0.67945 0.3048)
			(end 0.120396 0.3048)
			(stroke
				(width 0.1)
				(type default)
			)
			(layer "F.Fab")
		)
		(pad "1" smd circle
			(at -0.40005 0)
			(size 0 0)
			(layers "F.Cu" "F.Mask" "F.Paste")
			(net "P12V_SSD15")
		)
		(pad "2" smd circle
			(at 0.40005 0)
			(size 0 0)
			(layers "F.Cu" "F.Mask" "F.Paste")
			(net "GND")
		)
	)
	(footprint ""
		(layer "F.Cu")
		(at 162.5346 -30.03169 180)
		(property "Reference" "C289"
			(at 0 0 180)
			(layer "F.SilkS")
			(hide yes)
			(effects
				(font
					(size 1.27 1.27)
				)
			)
		)
		(property "Value" ""
			(at 0 0 180)
			(layer "F.Fab")
			(effects
				(font
					(size 1.27 1.27)
				)
			)
		)
		(duplicate_pad_numbers_are_jumpers no)
		(fp_line
			(start 0.299974 0.150114)
			(end -0.299974 0.150114)
			(stroke
				(width 0.1)
				(type default)
			)
			(layer "F.Fab")
		)
		(fp_line
			(start 0.299974 -0.150114)
			(end 0.299974 0.150114)
			(stroke
				(width 0.1)
				(type default)
			)
			(layer "F.Fab")
		)
		(fp_line
			(start -0.299974 0.150114)
			(end -0.299974 -0.150114)
			(stroke
				(width 0.1)
				(type default)
			)
			(layer "F.Fab")
		)
		(fp_line
			(start -0.299974 -0.150114)
			(end 0.299974 -0.150114)
			(stroke
				(width 0.1)
				(type default)
			)
			(layer "F.Fab")
		)
		(pad "1" smd rect
			(at -0.2667 0 180)
			(size 0.3048 0.381)
			(layers "F.Cu" "F.Mask" "F.Paste")
			(net "P5E_PEX1_STN2_TX_DN<41>")
		)
		(pad "2" smd rect
			(at 0.2667 0 180)
			(size 0.3048 0.381)
			(layers "F.Cu" "F.Mask" "F.Paste")
			(net "P5E_PEX1_STN2_TX_C_DN<41>")
		)
	)
	(footprint ""
		(layer "F.Cu")
		(at 379.633988 -7.884922)
		(property "Reference" "R5815"
			(at 0 0 0)
			(layer "F.SilkS")
			(hide yes)
			(effects
				(font
					(size 1.27 1.27)
				)
			)
		)
		(property "Value" ""
			(at 0 0 0)
			(layer "F.Fab")
			(effects
				(font
					(size 1.27 1.27)
				)
			)
		)
		(duplicate_pad_numbers_are_jumpers no)
		(fp_line
			(start -0.7874 -0.4064)
			(end 0.7874 -0.4064)
			(stroke
				(width 0.1524)
				(type default)
			)
			(layer "F.SilkS")
		)
		(fp_line
			(start -0.7874 0.4064)
			(end -0.7874 -0.4064)
			(stroke
				(width 0.1524)
				(type default)
			)
			(layer "F.SilkS")
		)
		(fp_line
			(start 0.7874 -0.4064)
			(end 0.7874 0.4064)
			(stroke
				(width 0.1524)
				(type default)
			)
			(layer "F.SilkS")
		)
		(fp_line
			(start 0.7874 0.4064)
			(end -0.7874 0.4064)
			(stroke
				(width 0.1524)
				(type default)
			)
			(layer "F.SilkS")
		)
		(fp_line
			(start -0.67945 -0.305054)
			(end -0.12065 -0.305054)
			(stroke
				(width 0.1)
				(type default)
			)
			(layer "F.Fab")
		)
		(fp_line
			(start -0.67945 0.3048)
			(end -0.67945 -0.305054)
			(stroke
				(width 0.1)
				(type default)
			)
			(layer "F.Fab")
		)
		(fp_line
			(start -0.12065 -0.305054)
			(end -0.12065 -0.2794)
			(stroke
				(width 0.1)
				(type default)
			)
			(layer "F.Fab")
		)
		(fp_line
			(start -0.12065 -0.2794)
			(end 0.12065 -0.2794)
			(stroke
				(width 0.1)
				(type default)
			)
			(layer "F.Fab")
		)
		(fp_line
			(start -0.12065 0.2794)
			(end -0.12065 0.3048)
			(stroke
				(width 0.1)
				(type default)
			)
			(layer "F.Fab")
		)
		(fp_line
			(start -0.12065 0.3048)
			(end -0.67945 0.3048)
			(stroke
				(width 0.1)
				(type default)
			)
			(layer "F.Fab")
		)
		(fp_line
			(start 0.120396 0.2794)
			(end -0.12065 0.2794)
			(stroke
				(width 0.1)
				(type default)
			)
			(layer "F.Fab")
		)
		(fp_line
			(start 0.120396 0.3048)
			(end 0.120396 0.2794)
			(stroke
				(width 0.1)
				(type default)
			)
			(layer "F.Fab")
		)
		(fp_line
			(start 0.12065 -0.3048)
			(end 0.67945 -0.3048)
			(stroke
				(width 0.1)
				(type default)
			)
			(layer "F.Fab")
		)
		(fp_line
			(start 0.12065 -0.2794)
			(end 0.12065 -0.3048)
			(stroke
				(width 0.1)
				(type default)
			)
			(layer "F.Fab")
		)
		(fp_line
			(start 0.67945 -0.3048)
			(end 0.67945 0.3048)
			(stroke
				(width 0.1)
				(type default)
			)
			(layer "F.Fab")
		)
		(fp_line
			(start 0.67945 0.3048)
			(end 0.120396 0.3048)
			(stroke
				(width 0.1)
				(type default)
			)
			(layer "F.Fab")
		)
		(pad "1" smd circle
			(at -0.40005 0)
			(size 0 0)
			(layers "F.Cu" "F.Mask" "F.Paste")
			(net "LM75_3_A0")
		)
		(pad "2" smd circle
			(at 0.40005 0)
			(size 0 0)
			(layers "F.Cu" "F.Mask" "F.Paste")
			(net "P3V3_AUX")
		)
	)
	(footprint ""
		(layer "F.Cu")
		(at 215.30056 -210.232244)
		(property "Reference" "R5524"
			(at 0 0 0)
			(layer "F.SilkS")
			(hide yes)
			(effects
				(font
					(size 1.27 1.27)
				)
			)
		)
		(property "Value" ""
			(at 0 0 0)
			(layer "F.Fab")
			(effects
				(font
					(size 1.27 1.27)
				)
			)
		)
		(duplicate_pad_numbers_are_jumpers no)
		(fp_line
			(start -0.7874 -0.4064)
			(end 0.7874 -0.4064)
			(stroke
				(width 0.1524)
				(type default)
			)
			(layer "F.SilkS")
		)
		(fp_line
			(start -0.7874 0.4064)
			(end -0.7874 -0.4064)
			(stroke
				(width 0.1524)
				(type default)
			)
			(layer "F.SilkS")
		)
		(fp_line
			(start 0.7874 -0.4064)
			(end 0.7874 0.4064)
			(stroke
				(width 0.1524)
				(type default)
			)
			(layer "F.SilkS")
		)
		(fp_line
			(start 0.7874 0.4064)
			(end -0.7874 0.4064)
			(stroke
				(width 0.1524)
				(type default)
			)
			(layer "F.SilkS")
		)
		(fp_line
			(start -0.67945 -0.305054)
			(end -0.12065 -0.305054)
			(stroke
				(width 0.1)
				(type default)
			)
			(layer "F.Fab")
		)
		(fp_line
			(start -0.67945 0.3048)
			(end -0.67945 -0.305054)
			(stroke
				(width 0.1)
				(type default)
			)
			(layer "F.Fab")
		)
		(fp_line
			(start -0.12065 -0.305054)
			(end -0.12065 -0.2794)
			(stroke
				(width 0.1)
				(type default)
			)
			(layer "F.Fab")
		)
		(fp_line
			(start -0.12065 -0.2794)
			(end 0.12065 -0.2794)
			(stroke
				(width 0.1)
				(type default)
			)
			(layer "F.Fab")
		)
		(fp_line
			(start -0.12065 0.2794)
			(end -0.12065 0.3048)
			(stroke
				(width 0.1)
				(type default)
			)
			(layer "F.Fab")
		)
		(fp_line
			(start -0.12065 0.3048)
			(end -0.67945 0.3048)
			(stroke
				(width 0.1)
				(type default)
			)
			(layer "F.Fab")
		)
		(fp_line
			(start 0.120396 0.2794)
			(end -0.12065 0.2794)
			(stroke
				(width 0.1)
				(type default)
			)
			(layer "F.Fab")
		)
		(fp_line
			(start 0.120396 0.3048)
			(end 0.120396 0.2794)
			(stroke
				(width 0.1)
				(type default)
			)
			(layer "F.Fab")
		)
		(fp_line
			(start 0.12065 -0.3048)
			(end 0.67945 -0.3048)
			(stroke
				(width 0.1)
				(type default)
			)
			(layer "F.Fab")
		)
		(fp_line
			(start 0.12065 -0.2794)
			(end 0.12065 -0.3048)
			(stroke
				(width 0.1)
				(type default)
			)
			(layer "F.Fab")
		)
		(fp_line
			(start 0.67945 -0.3048)
			(end 0.67945 0.3048)
			(stroke
				(width 0.1)
				(type default)
			)
			(layer "F.Fab")
		)
		(fp_line
			(start 0.67945 0.3048)
			(end 0.120396 0.3048)
			(stroke
				(width 0.1)
				(type default)
			)
			(layer "F.Fab")
		)
		(pad "1" smd circle
			(at -0.40005 0)
			(size 0 0)
			(layers "F.Cu" "F.Mask" "F.Paste")
			(net "GND")
		)
		(pad "2" smd circle
			(at 0.40005 0)
			(size 0 0)
			(layers "F.Cu" "F.Mask" "F.Paste")
			(net "RST_SSD_LED_IOEXP_R_N")
		)
	)
	(footprint ""
		(layer "F.Cu")
		(at 363.596936 -118.378986 -90)
		(property "Reference" "R6042"
			(at 0 0 270)
			(layer "F.SilkS")
			(hide yes)
			(effects
				(font
					(size 1.27 1.27)
				)
			)
		)
		(property "Value" ""
			(at 0 0 270)
			(layer "F.Fab")
			(effects
				(font
					(size 1.27 1.27)
				)
			)
		)
		(duplicate_pad_numbers_are_jumpers no)
		(fp_line
			(start -0.7874 0.4064)
			(end -0.7874 -0.4064)
			(stroke
				(width 0.1524)
				(type default)
			)
			(layer "F.SilkS")
		)
		(fp_line
			(start 0.7874 0.4064)
			(end -0.7874 0.4064)
			(stroke
				(width 0.1524)
				(type default)
			)
			(layer "F.SilkS")
		)
		(fp_line
			(start -0.7874 -0.4064)
			(end 0.7874 -0.4064)
			(stroke
				(width 0.1524)
				(type default)
			)
			(layer "F.SilkS")
		)
		(fp_line
			(start 0.7874 -0.4064)
			(end 0.7874 0.4064)
			(stroke
				(width 0.1524)
				(type default)
			)
			(layer "F.SilkS")
		)
		(fp_line
			(start -0.67945 0.3048)
			(end -0.67945 -0.305054)
			(stroke
				(width 0.1)
				(type default)
			)
			(layer "F.Fab")
		)
		(fp_line
			(start -0.12065 0.3048)
			(end -0.67945 0.3048)
			(stroke
				(width 0.1)
				(type default)
			)
			(layer "F.Fab")
		)
		(fp_line
			(start 0.120396 0.3048)
			(end 0.120396 0.2794)
			(stroke
				(width 0.1)
				(type default)
			)
			(layer "F.Fab")
		)
		(fp_line
			(start 0.67945 0.3048)
			(end 0.120396 0.3048)
			(stroke
				(width 0.1)
				(type default)
			)
			(layer "F.Fab")
		)
		(fp_line
			(start -0.12065 0.2794)
			(end -0.12065 0.3048)
			(stroke
				(width 0.1)
				(type default)
			)
			(layer "F.Fab")
		)
		(fp_line
			(start 0.120396 0.2794)
			(end -0.12065 0.2794)
			(stroke
				(width 0.1)
				(type default)
			)
			(layer "F.Fab")
		)
		(fp_line
			(start -0.12065 -0.2794)
			(end 0.12065 -0.2794)
			(stroke
				(width 0.1)
				(type default)
			)
			(layer "F.Fab")
		)
		(fp_line
			(start 0.12065 -0.2794)
			(end 0.12065 -0.3048)
			(stroke
				(width 0.1)
				(type default)
			)
			(layer "F.Fab")
		)
		(fp_line
			(start 0.12065 -0.3048)
			(end 0.67945 -0.3048)
			(stroke
				(width 0.1)
				(type default)
			)
			(layer "F.Fab")
		)
		(fp_line
			(start 0.67945 -0.3048)
			(end 0.67945 0.3048)
			(stroke
				(width 0.1)
				(type default)
			)
			(layer "F.Fab")
		)
		(fp_line
			(start -0.67945 -0.305054)
			(end -0.12065 -0.305054)
			(stroke
				(width 0.1)
				(type default)
			)
			(layer "F.Fab")
		)
		(fp_line
			(start -0.12065 -0.305054)
			(end -0.12065 -0.2794)
			(stroke
				(width 0.1)
				(type default)
			)
			(layer "F.Fab")
		)
		(pad "1" smd circle
			(at -0.40005 0 270)
			(size 0 0)
			(layers "F.Cu" "F.Mask" "F.Paste")
			(net "HP_NIC6_EN")
		)
		(pad "2" smd circle
			(at 0.40005 0 270)
			(size 0 0)
			(layers "F.Cu" "F.Mask" "F.Paste")
			(net "P3V3_NIC6_CO_EN")
		)
	)
	(footprint ""
		(layer "F.Cu")
		(at 121.163588 -350.098614 90)
		(property "Reference" "C348"
			(at 0 0 90)
			(layer "F.SilkS")
			(hide yes)
			(effects
				(font
					(size 1.27 1.27)
				)
			)
		)
		(property "Value" ""
			(at 0 0 90)
			(layer "F.Fab")
			(effects
				(font
					(size 1.27 1.27)
				)
			)
		)
		(duplicate_pad_numbers_are_jumpers no)
		(fp_line
			(start 0.299974 -0.150114)
			(end 0.299974 0.150114)
			(stroke
				(width 0.1)
				(type default)
			)
			(layer "F.Fab")
		)
		(fp_line
			(start -0.299974 -0.150114)
			(end 0.299974 -0.150114)
			(stroke
				(width 0.1)
				(type default)
			)
			(layer "F.Fab")
		)
		(fp_line
			(start 0.299974 0.150114)
			(end -0.299974 0.150114)
			(stroke
				(width 0.1)
				(type default)
			)
			(layer "F.Fab")
		)
		(fp_line
			(start -0.299974 0.150114)
			(end -0.299974 -0.150114)
			(stroke
				(width 0.1)
				(type default)
			)
			(layer "F.Fab")
		)
		(pad "1" smd rect
			(at -0.2667 0 90)
			(size 0.3048 0.381)
			(layers "F.Cu" "F.Mask" "F.Paste")
			(net "P5E_PEX1_STN6_TX_DP<107>")
		)
		(pad "2" smd rect
			(at 0.2667 0 90)
			(size 0.3048 0.381)
			(layers "F.Cu" "F.Mask" "F.Paste")
			(net "P5E_PEX1_STN6_TX_C_DP<107>")
		)
	)
)
